(kicad_pcb
	(version 20241229)
	(generator "pcbnew")
	(generator_version "9.0")
	(general
		(thickness 1.63)
		(legacy_teardrops no)
	)
	(paper "A4")
	(title_block
		(title "CM4 Baseboard")
		(date "2026-01-05")
		(rev "1.1.1")
		(company "Antmicro Ltd")
		(comment 1 "www.antmicro.com")
		(comment 9 "footprints 112-116 of 506")
	)
	(layers
		(0 "F.Cu" signal)
		(4 "In1.Cu" power)
		(6 "In2.Cu" power)
		(8 "In3.Cu" signal)
		(10 "In4.Cu" signal)
		(2 "B.Cu" signal)
		(9 "F.Adhes" user "F.Adhesive")
		(11 "B.Adhes" user "B.Adhesive")
		(13 "F.Paste" user)
		(15 "B.Paste" user)
		(5 "F.SilkS" user "F.Silkscreen")
		(7 "B.SilkS" user "B.Silkscreen")
		(1 "F.Mask" user)
		(3 "B.Mask" user)
		(17 "Dwgs.User" user "User.Drawings")
		(19 "Cmts.User" user "User.Comments")
		(21 "Eco1.User" user "User.Eco1")
		(23 "Eco2.User" user "User.Eco2")
		(25 "Edge.Cuts" user)
		(27 "Margin" user)
		(31 "F.CrtYd" user "F.Courtyard")
		(29 "B.CrtYd" user "B.Courtyard")
		(35 "F.Fab" user)
		(33 "B.Fab" user)
	)
	(footprint "antmicro-footprints:R_0402_1005Metric"
		(layer "F.Cu")
		(at 77.317962 148.6915 90)
		(descr "Resistor SMD 0402")
		(tags "resistor SMD 0402")
		(property "Reference" "R207"
			(at -3.585 0.66 90)
			(layer "F.SilkS")
			(effects
				(font
					(size 0.7 0.7)
					(thickness 0.15)
				)
				(justify left bottom)
			)
		)
		(property "Value" "R_1k_0402"
			(at -1.011843 1.772047 90)
			(layer "F.Fab")
			(effects
				(font
					(size 0.7 0.7)
					(thickness 0.15)
				)
				(justify left bottom)
			)
		)
		(property "Datasheet" "https://www.bourns.com/docs/product-datasheets/cr.pdf"
			(at 0 0 90)
			(layer "F.Fab")
			(hide yes)
			(effects
				(font
					(size 1.27 1.27)
					(thickness 0.15)
				)
			)
		)
		(property "MPN" "CR0402-FX-1001GLF"
			(at 0 0 90)
			(unlocked yes)
			(layer "F.Fab")
			(hide yes)
			(effects
				(font
					(size 1 1)
					(thickness 0.15)
				)
			)
		)
		(property "Manufacturer" "Bourns"
			(at 0 0 90)
			(unlocked yes)
			(layer "F.Fab")
			(hide yes)
			(effects
				(font
					(size 1 1)
					(thickness 0.15)
				)
			)
		)
		(property "License" "Apache-2.0"
			(at 0 0 90)
			(unlocked yes)
			(layer "F.Fab")
			(hide yes)
			(effects
				(font
					(size 1 1)
					(thickness 0.15)
				)
			)
		)
		(property "Author" "Antmicro"
			(at 0 0 90)
			(unlocked yes)
			(layer "F.Fab")
			(hide yes)
			(effects
				(font
					(size 1 1)
					(thickness 0.15)
				)
			)
		)
		(property "Val" "1k"
			(at 0 0 90)
			(unlocked yes)
			(layer "F.Fab")
			(hide yes)
			(effects
				(font
					(size 1 1)
					(thickness 0.15)
				)
			)
		)
		(property "Tolerance" "1%"
			(at 0 0 90)
			(unlocked yes)
			(layer "F.Fab")
			(hide yes)
			(effects
				(font
					(size 1 1)
					(thickness 0.15)
				)
			)
		)
		(sheetname "/Compute module/")
		(sheetfile "compute-module.kicad_sch")
		(attr smd)
		(fp_rect
			(start -0.925 -0.47)
			(end 0.925 0.47)
			(stroke
				(width 0.05)
				(type default)
			)
			(fill no)
			(layer "F.CrtYd")
		)
		(fp_rect
			(start -0.5 -0.25)
			(end 0.5 0.25)
			(stroke
				(width 0.15)
				(type solid)
			)
			(fill no)
			(layer "F.Fab")
		)
		(fp_text user "Author: Antmicro"
			(at -0.95 4.169 90)
			(layer "F.Fab")
			(effects
				(font
					(size 0.7 0.7)
					(thickness 0.15)
				)
				(justify left bottom)
			)
		)
		(fp_text user "License: Apache-2.0"
			(at -0.95 5.169 90)
			(layer "F.Fab")
			(effects
				(font
					(size 0.7 0.7)
					(thickness 0.15)
				)
				(justify left bottom)
			)
		)
		(fp_text user "${REFERENCE}"
			(at -0.95 3.168 90)
			(layer "F.Fab")
			(effects
				(font
					(size 0.7 0.7)
					(thickness 0.15)
				)
				(justify left bottom)
			)
		)
		(pad "1" smd roundrect
			(at -0.48 0 90)
			(size 0.59 0.64)
			(layers "F.Cu" "F.Mask" "F.Paste")
			(roundrect_rratio 0.25)
			(net 137 "Net-(J201-Pad21)")
			(pintype "passive")
		)
		(pad "2" smd roundrect
			(at 0.48 0 90)
			(size 0.59 0.64)
			(layers "F.Cu" "F.Mask" "F.Paste")
			(roundrect_rratio 0.25)
			(net 445 "Net-(D201-C)")
			(pintype "passive")
		)
	)
	(footprint "antmicro-footprints:R_0402_1005Metric"
		(layer "F.Cu")
		(at 82.667962 120.7415 180)
		(descr "Resistor SMD 0402")
		(tags "resistor SMD 0402")
		(property "Reference" "R902"
			(at -1.03 -1.205 0)
			(layer "F.SilkS")
			(effects
				(font
					(size 0.7 0.7)
					(thickness 0.15)
				)
				(justify right bottom)
			)
		)
		(property "Value" "R_1k_0402"
			(at -1.011843 1.772047 0)
			(layer "F.Fab")
			(effects
				(font
					(size 0.7 0.7)
					(thickness 0.15)
				)
				(justify right bottom)
			)
		)
		(property "Datasheet" "https://www.bourns.com/docs/product-datasheets/cr.pdf"
			(at 0 0 180)
			(layer "F.Fab")
			(hide yes)
			(effects
				(font
					(size 1.27 1.27)
					(thickness 0.15)
				)
			)
		)
		(property "MPN" "CR0402-FX-1001GLF"
			(at 0 0 180)
			(unlocked yes)
			(layer "F.Fab")
			(hide yes)
			(effects
				(font
					(size 1 1)
					(thickness 0.15)
				)
			)
		)
		(property "Manufacturer" "Bourns"
			(at 0 0 180)
			(unlocked yes)
			(layer "F.Fab")
			(hide yes)
			(effects
				(font
					(size 1 1)
					(thickness 0.15)
				)
			)
		)
		(property "License" "Apache-2.0"
			(at 0 0 180)
			(unlocked yes)
			(layer "F.Fab")
			(hide yes)
			(effects
				(font
					(size 1 1)
					(thickness 0.15)
				)
			)
		)
		(property "Author" "Antmicro"
			(at 0 0 180)
			(unlocked yes)
			(layer "F.Fab")
			(hide yes)
			(effects
				(font
					(size 1 1)
					(thickness 0.15)
				)
			)
		)
		(property "Val" "1k"
			(at 0 0 180)
			(unlocked yes)
			(layer "F.Fab")
			(hide yes)
			(effects
				(font
					(size 1 1)
					(thickness 0.15)
				)
			)
		)
		(property "Tolerance" "1%"
			(at 0 0 180)
			(unlocked yes)
			(layer "F.Fab")
			(hide yes)
			(effects
				(font
					(size 1 1)
					(thickness 0.15)
				)
			)
		)
		(sheetname "/USB/")
		(sheetfile "usb.kicad_sch")
		(attr smd)
		(fp_rect
			(start -0.925 -0.47)
			(end 0.925 0.47)
			(stroke
				(width 0.05)
				(type default)
			)
			(fill no)
			(layer "F.CrtYd")
		)
		(fp_rect
			(start -0.5 -0.25)
			(end 0.5 0.25)
			(stroke
				(width 0.15)
				(type solid)
			)
			(fill no)
			(layer "F.Fab")
		)
		(fp_text user "License: Apache-2.0"
			(at -0.95 5.169 180)
			(layer "F.Fab")
			(effects
				(font
					(size 0.7 0.7)
					(thickness 0.15)
				)
				(justify left bottom)
			)
		)
		(fp_text user "Author: Antmicro"
			(at -0.95 4.169 180)
			(layer "F.Fab")
			(effects
				(font
					(size 0.7 0.7)
					(thickness 0.15)
				)
				(justify left bottom)
			)
		)
		(fp_text user "${REFERENCE}"
			(at -0.95 3.168 180)
			(layer "F.Fab")
			(effects
				(font
					(size 0.7 0.7)
					(thickness 0.15)
				)
				(justify left bottom)
			)
		)
		(pad "1" smd roundrect
			(at -0.48 0 180)
			(size 0.59 0.64)
			(layers "F.Cu" "F.Mask" "F.Paste")
			(roundrect_rratio 0.25)
			(net 483 "Net-(D906-A)")
			(pintype "passive")
		)
		(pad "2" smd roundrect
			(at 0.48 0 180)
			(size 0.59 0.64)
			(layers "F.Cu" "F.Mask" "F.Paste")
			(roundrect_rratio 0.25)
			(net 10 "+5V")
			(pintype "passive")
		)
	)
	(footprint "antmicro-footprints:TP_SMD_0.75mm"
		(layer "F.Cu")
		(at 130.39 156.3)
		(property "Reference" "TP602"
			(at -2.85 -0.425 180)
			(layer "F.SilkS")
			(effects
				(font
					(size 0.7 0.7)
					(thickness 0.15)
				)
				(justify left bottom)
			)
		)
		(property "Value" "TP_0.75mm_SMD"
			(at 0 1.2 0)
			(layer "F.Fab")
			(effects
				(font
					(size 0.7 0.7)
					(thickness 0.15)
				)
				(justify left bottom)
			)
		)
		(property "MPN" ""
			(at 0 0 0)
			(unlocked yes)
			(layer "F.Fab")
			(hide yes)
			(effects
				(font
					(size 1 1)
					(thickness 0.15)
				)
			)
		)
		(property "Manufacturer" ""
			(at 0 0 0)
			(unlocked yes)
			(layer "F.Fab")
			(hide yes)
			(effects
				(font
					(size 1 1)
					(thickness 0.15)
				)
			)
		)
		(property "Author" "Antmicro"
			(at 0 0 0)
			(unlocked yes)
			(layer "F.Fab")
			(hide yes)
			(effects
				(font
					(size 1 1)
					(thickness 0.15)
				)
			)
		)
		(property "License" "Apache-2.0"
			(at 0 0 0)
			(unlocked yes)
			(layer "F.Fab")
			(hide yes)
			(effects
				(font
					(size 1 1)
					(thickness 0.15)
				)
			)
		)
		(sheetname "/CSI/")
		(sheetfile "csi.kicad_sch")
		(attr exclude_from_pos_files exclude_from_bom)
		(fp_circle
			(center 0 0)
			(end 0.475 0)
			(stroke
				(width 0.05)
				(type default)
			)
			(fill no)
			(layer "F.CrtYd")
		)
		(fp_text user "${REFERENCE}"
			(at -0.4 2.7 0)
			(layer "F.Fab")
			(effects
				(font
					(size 0.7 0.7)
					(thickness 0.15)
				)
				(justify left bottom)
			)
		)
		(fp_text user "Author: Antmicro"
			(at -0.4 3.901 0)
			(layer "F.Fab")
			(effects
				(font
					(size 0.7 0.7)
					(thickness 0.15)
				)
				(justify left bottom)
			)
		)
		(fp_text user "License: Apache-2.0"
			(at -0.4 5.101 0)
			(layer "F.Fab")
			(effects
				(font
					(size 0.7 0.7)
					(thickness 0.15)
				)
				(justify left bottom)
			)
		)
		(pad "1" smd circle
			(at 0 0)
			(size 0.75 0.75)
			(layers "F.Cu" "F.Mask")
			(net 371 "Net-(U602-FLG)")
			(pinfunction "1")
			(pintype "passive")
		)
	)
	(footprint "antmicro-footprints:R_0402_1005Metric"
		(layer "F.Cu")
		(at 51.097962 134.8565 180)
		(descr "Resistor SMD 0402")
		(tags "resistor SMD 0402")
		(property "Reference" "R408"
			(at -0.743438 -1.3891 0)
			(layer "F.SilkS")
			(effects
				(font
					(size 0.7 0.7)
					(thickness 0.15)
				)
				(justify right bottom)
			)
		)
		(property "Value" "R_10k_0402"
			(at -1.011843 1.772047 0)
			(layer "F.Fab")
			(effects
				(font
					(size 0.7 0.7)
					(thickness 0.15)
				)
				(justify right bottom)
			)
		)
		(property "Datasheet" "https://www.bourns.com/docs/product-datasheets/cr.pdf"
			(at 0 0 180)
			(layer "F.Fab")
			(hide yes)
			(effects
				(font
					(size 1.27 1.27)
					(thickness 0.15)
				)
			)
		)
		(property "Manufacturer" "Bourns"
			(at 0 0 180)
			(unlocked yes)
			(layer "F.Fab")
			(hide yes)
			(effects
				(font
					(size 1 1)
					(thickness 0.15)
				)
			)
		)
		(property "MPN" "CR0402-FX-1002GLF"
			(at 0 0 180)
			(unlocked yes)
			(layer "F.Fab")
			(hide yes)
			(effects
				(font
					(size 1 1)
					(thickness 0.15)
				)
			)
		)
		(property "Val" "10k"
			(at 0 0 180)
			(unlocked yes)
			(layer "F.Fab")
			(hide yes)
			(effects
				(font
					(size 1 1)
					(thickness 0.15)
				)
			)
		)
		(property "License" "Apache-2.0"
			(at 0 0 180)
			(unlocked yes)
			(layer "F.Fab")
			(hide yes)
			(effects
				(font
					(size 1 1)
					(thickness 0.15)
				)
			)
		)
		(property "Author" "Antmicro"
			(at 0 0 180)
			(unlocked yes)
			(layer "F.Fab")
			(hide yes)
			(effects
				(font
					(size 1 1)
					(thickness 0.15)
				)
			)
		)
		(property "Tolerance" "1%"
			(at 0 0 180)
			(unlocked yes)
			(layer "F.Fab")
			(hide yes)
			(effects
				(font
					(size 1 1)
					(thickness 0.15)
				)
			)
		)
		(sheetname "/Ethernet/")
		(sheetfile "ethernet.kicad_sch")
		(attr smd)
		(fp_rect
			(start -0.925 -0.47)
			(end 0.925 0.47)
			(stroke
				(width 0.05)
				(type default)
			)
			(fill no)
			(layer "F.CrtYd")
		)
		(fp_rect
			(start -0.5 -0.25)
			(end 0.5 0.25)
			(stroke
				(width 0.15)
				(type solid)
			)
			(fill no)
			(layer "F.Fab")
		)
		(fp_text user "Author: Antmicro"
			(at -0.95 4.169 180)
			(layer "F.Fab")
			(effects
				(font
					(size 0.7 0.7)
					(thickness 0.15)
				)
				(justify left bottom)
			)
		)
		(fp_text user "${REFERENCE}"
			(at -0.95 3.168 180)
			(layer "F.Fab")
			(effects
				(font
					(size 0.7 0.7)
					(thickness 0.15)
				)
				(justify left bottom)
			)
		)
		(fp_text user "License: Apache-2.0"
			(at -0.95 5.169 180)
			(layer "F.Fab")
			(effects
				(font
					(size 0.7 0.7)
					(thickness 0.15)
				)
				(justify left bottom)
			)
		)
		(pad "1" smd roundrect
			(at -0.48 0 180)
			(size 0.59 0.64)
			(layers "F.Cu" "F.Mask" "F.Paste")
			(roundrect_rratio 0.25)
			(net 339 "/Ethernet/POE_ACTIVE")
			(pintype "passive")
		)
		(pad "2" smd roundrect
			(at 0.48 0 180)
			(size 0.59 0.64)
			(layers "F.Cu" "F.Mask" "F.Paste")
			(roundrect_rratio 0.25)
			(net 363 "/Ethernet/PG")
			(pintype "passive")
		)
	)
	(footprint "antmicro-footprints:LED_0603_1608Metric_G"
		(layer "F.Cu")
		(at 79.617962 124.5765)
		(descr "LED SMD 0603 Green")
		(tags "LED SMD 0603 Green")
		(property "Reference" "D907"
			(at -0.5 -0.66 0)
			(layer "F.SilkS")
			(effects
				(font
					(size 0.7 0.7)
					(thickness 0.15)
				)
				(justify left bottom)
			)
		)
		(property "Value" "LED_G_0603_KP-1608CGCK"
			(at -0.001 1.599 0)
			(layer "F.Fab")
			(effects
				(font
					(size 0.7 0.7)
					(thickness 0.15)
				)
				(justify left bottom)
			)
		)
		(property "Datasheet" "http://www.kingbright.com/attachments/file/psearch//000/00/00/KP-1608CGCK(Ver.23B).pdf"
			(at 0 0 0)
			(layer "F.Fab")
			(hide yes)
			(effects
				(font
					(size 1.27 1.27)
					(thickness 0.15)
				)
			)
		)
		(property "MPN" "KP-1608CGCK"
			(at 0 0 0)
			(unlocked yes)
			(layer "F.Fab")
			(hide yes)
			(effects
				(font
					(size 1 1)
					(thickness 0.15)
				)
			)
		)
		(property "Manufacturer" "Kingbright"
			(at 0 0 0)
			(unlocked yes)
			(layer "F.Fab")
			(hide yes)
			(effects
				(font
					(size 1 1)
					(thickness 0.15)
				)
			)
		)
		(property "Color" "Green"
			(at 0 0 0)
			(unlocked yes)
			(layer "F.Fab")
			(hide yes)
			(effects
				(font
					(size 1 1)
					(thickness 0.15)
				)
			)
		)
		(property "Author" "Antmicro"
			(at 0 0 0)
			(unlocked yes)
			(layer "F.Fab")
			(hide yes)
			(effects
				(font
					(size 1 1)
					(thickness 0.15)
				)
			)
		)
		(property "License" "Apache-2.0"
			(at 0 0 0)
			(unlocked yes)
			(layer "F.Fab")
			(hide yes)
			(effects
				(font
					(size 1 1)
					(thickness 0.15)
				)
			)
		)
		(sheetname "/USB/")
		(sheetfile "usb.kicad_sch")
		(attr smd)
		(fp_line
			(start -1.18 -0.319)
			(end -1.18 0.321)
			(stroke
				(width 0.15)
				(type solid)
			)
			(layer "F.SilkS")
		)
		(fp_line
			(start -0.094672 0.001008)
			(end -0.24 0.001008)
			(stroke
				(width 0.1)
				(type solid)
			)
			(layer "F.SilkS")
		)
		(fp_line
			(start -0.094672 0.001008)
			(end 0.105328 -0.198992)
			(stroke
				(width 0.1)
				(type solid)
			)
			(layer "F.SilkS")
		)
		(fp_line
			(start -0.094672 0.201008)
			(end -0.094672 -0.198992)
			(stroke
				(width 0.1)
				(type solid)
			)
			(layer "F.SilkS")
		)
		(fp_line
			(start 0.105328 0.001008)
			(end 0.24 0.001)
			(stroke
				(width 0.1)
				(type solid)
			)
			(layer "F.SilkS")
		)
		(fp_line
			(start 0.105328 0.201008)
			(end -0.094672 0.001008)
			(stroke
				(width 0.1)
				(type solid)
			)
			(layer "F.SilkS")
		)
		(fp_line
			(start 0.105328 0.201008)
			(end 0.105328 -0.198992)
			(stroke
				(width 0.1)
				(type solid)
			)
			(layer "F.SilkS")
		)
		(fp_line
			(start 0.22 -0.35)
			(end -0.22 -0.35)
			(stroke
				(width 0.15)
				(type solid)
			)
			(layer "F.SilkS")
		)
		(fp_line
			(start 0.22 0.35)
			(end -0.22 0.35)
			(stroke
				(width 0.15)
				(type solid)
			)
			(layer "F.SilkS")
		)
		(fp_rect
			(start 1.25 0.65)
			(end -1.25 -0.65)
			(stroke
				(width 0.05)
				(type solid)
			)
			(fill no)
			(layer "F.CrtYd")
		)
		(fp_line
			(start -0.199 -0.202)
			(end -0.199 0.1)
			(stroke
				(width 0.15)
				(type solid)
			)
			(layer "F.Fab")
		)
		(fp_line
			(start -0.199 0)
			(end -0.597 0)
			(stroke
				(width 0.15)
				(type solid)
			)
			(layer "F.Fab")
		)
		(fp_line
			(start -0.199 0.2)
			(end -0.199 0.1)
			(stroke
				(width 0.15)
				(type solid)
			)
			(layer "F.Fab")
		)
		(fp_line
			(start -0.101 0)
			(end 0.201 0.2)
			(stroke
				(width 0.15)
				(type solid)
			)
			(layer "F.Fab")
		)
		(fp_line
			(start 0.201 -0.202)
			(end -0.101 0)
			(stroke
				(width 0.15)
				(type solid)
			)
			(layer "F.Fab")
		)
		(fp_line
			(start 0.201 0)
			(end 0.201 -0.202)
			(stroke
				(width 0.15)
				(type solid)
			)
			(layer "F.Fab")
		)
		(fp_line
			(start 0.201 0.2)
			(end 0.201 0)
			(stroke
				(width 0.15)
				(type solid)
			)
			(layer "F.Fab")
		)
		(fp_line
			(start 0.599 0)
			(end 0.201 0)
			(stroke
				(width 0.15)
				(type solid)
			)
			(layer "F.Fab")
		)
		(fp_rect
			(start 0.848 0.4)
			(end -0.85 -0.402)
			(stroke
				(width 0.15)
				(type solid)
			)
			(fill no)
			(layer "F.Fab")
		)
		(fp_text user "License: Apache-2.0"
			(at -1.4224 3.599 0)
			(layer "F.Fab")
			(effects
				(font
					(size 0.7 0.7)
					(thickness 0.15)
				)
				(justify left bottom)
			)
		)
		(fp_text user "Author: Antmicro"
			(at -1.4224 4.799 0)
			(layer "F.Fab")
			(effects
				(font
					(size 0.7 0.7)
					(thickness 0.15)
				)
				(justify left bottom)
			)
		)
		(fp_text user "${REFERENCE}"
			(at -1.4224 5.999 0)
			(layer "F.Fab")
			(effects
				(font
					(size 0.7 0.7)
					(thickness 0.15)
				)
				(justify left bottom)
			)
		)
		(pad "1" smd roundrect
			(at -0.7 0 180)
			(size 0.8 1)
			(layers "F.Cu" "F.Mask" "F.Paste")
			(roundrect_rratio 0.2)
			(net 3 "GND")
			(pinfunction "C")
			(pintype "passive")
		)
		(pad "2" smd roundrect
			(at 0.7 0 180)
			(size 0.8 1)
			(layers "F.Cu" "F.Mask" "F.Paste")
			(roundrect_rratio 0.2)
			(net 484 "Net-(D907-A)")
			(pinfunction "A")
			(pintype "passive")
		)
	)
)
